# 4HDD Backplane_BOM.xls — Sheet0 (bom)
| Description | Qty | Location |
| HEAD ML 1R4P G88MPB04102CEU ,LCP | 1 | CN2 |
| CONN CTR 2R29P 10031077-001LF | 4 | SATA1 SATA2 SATA3 SATA4 |
| TIOGA PASS CHANNEL HDD BP BD 4 CON SA S | 1 |  |
| HEAD ML 1R15P T1M-15-F-SV-L-P SMD | 1 | CN1 |
| IC FETMOS DMN63D1LDW-7 NC SOT-363 ESD 2K | 4 | U11 U13 U15 U8 |
| CONN CTR 36P MINI SAS G40H2132212HR-W | 1 | MISAS1 |
| CHIP RES 10K J 1/16W 0402 | 6 | R1 R151 R154 R2 R7 R8 |
| CHIP RES 33K J 1/16W 0402 | 1 | R153 |
| CHIP RES 4.7K J 1/16W 0402 | 9 | R137 R138 R142 R143 R146 R147 R152 R155 R156 |
| CHIP RES 10 F 1/10W 0603 | 8 | R10 R11 R12 R3 R4 R5 R6 R9 |
| CHIP RES 1.2K F 1/10W0603(ROHS | 1 | PR1 |
| CHIP RES 200K F 1/16W 0402 | 4 | R140 R149 R159 R160 |
| CHIP RES 300K F 1/16W 0402 | 4 | R139 R144 R148 R157 |
| IC CMOS SN74LVC1G08DCKR SC-70 | 2 | U16 U17 |
| CHIP CAP C 0.01U 50V K0402 X7R | 4 | C1 C13 C14 C3 |
| CHIP CAP C 0.1U 25V K0603 X7R | 1 | C35 |
| CHIP CAP C 0.1U 25V K0402 X7R | 4 | C29 C30 C31 C34 |
| CHIP CAP C 0.1U 25V K0402 X5R | 13 | C10 C12 C17 C18 C21 C24 C25 C26 C27 C28 C4 C6 PC2 |
| CHIP CAP 0.1UF J 16V 0402 X7R | 1 | C32 |
| CHIP CAP C 1U 6.3V K0402 X5R | 1 | PC1 |
| CHIP CAP C 10U 25V K1206 X5R | 8 | C11 C19 C20 C22 C23 C7 C8 C9 |
| CHIP CAP C 10U 10V K0805 X5R 13" REEL | 4 | C15 C16 C2 C5 |
| CHIP CAP C 22U 25V M0805 X5R T1.45 | 2 | TC1 TC2 |
| DIODE ZEN MMPZ5228BPT SOD-323 | 1 | PD1 |
| DIODE S.B LRB551V-30T1G SOD-323 | 4 | D1 D2 D3 D4 |
| FET MOS P2003EVG PC SO-8 | 4 | U10 U12 U14 U9 |
| XTOR MMBT3904W NPN SOT-323 | 1 | PQ1 |
| PCB 17301-SA TP CHANNEL HDD BP CARD 6L | 1 |  |
